(kicad_pcb
	(version 20260206)
	(generator "pcbnew")
	(generator_version "10.0")
	(general
		(thickness 1.6)
		(legacy_teardrops no)
	)
	(paper "A4")
	(title_block
		(title "03242023_DA0F0TMBIJ0_F0T_Motherboard_J_brd_V01_OCP.brd")
		(comment 1 "Grand Teton / footprints 3199-3204 of 6105")
	)
	(layers
		(0 "F.Cu" signal "TOP")
		(4 "In1.Cu" signal "GND")
		(6 "In2.Cu" signal "IN1")
		(8 "In3.Cu" signal "GND1")
		(10 "In4.Cu" signal "IN2")
		(12 "In5.Cu" signal "GND2")
		(14 "In6.Cu" signal "IN3")
		(16 "In7.Cu" signal "GND3")
		(18 "In8.Cu" signal "VCC")
		(20 "In9.Cu" signal "VCC1")
		(22 "In10.Cu" signal "GND4")
		(24 "In11.Cu" signal "IN4")
		(26 "In12.Cu" signal "GND5")
		(28 "In13.Cu" signal "IN5")
		(30 "In14.Cu" signal "GND6")
		(32 "In15.Cu" signal "IN6")
		(34 "In16.Cu" signal "GND7")
		(2 "B.Cu" signal "BOTTOM")
		(9 "F.Adhes" user "F.Adhesive")
		(11 "B.Adhes" user "B.Adhesive")
		(13 "F.Paste" user "Package Geometry/Pastemask Top")
		(15 "B.Paste" user "Package Geometry/Pastemask Bottom")
		(5 "F.SilkS" user "Ref Des/Silkscreen Top")
		(7 "B.SilkS" user "Ref Des/Silkscreen Bottom")
		(1 "F.Mask" user "Board Geometry/Soldermask Top")
		(3 "B.Mask" user "Board Geometry/Soldermask Bottom")
		(17 "Dwgs.User" user "User.Drawings")
		(19 "Cmts.User" user "User.Comments")
		(21 "Eco1.User" user "User.Eco1")
		(23 "Eco2.User" user "User.Eco2")
		(25 "Edge.Cuts" user "Board Geometry/Outline")
		(27 "Margin" user)
		(31 "F.CrtYd" user "Package Geometry/Place Bound Top")
		(29 "B.CrtYd" user "Package Geometry/Place Bound Bottom")
		(35 "F.Fab" user "Ref Des/Assembly Top")
		(33 "B.Fab" user "Ref Des/Assembly Bottom")
	)
	(footprint ""
		(layer "F.Cu")
		(at 279.5778 -72.050148)
		(property "Reference" "PC1230"
			(at 0 0 0)
			(layer "F.SilkS")
			(hide yes)
			(effects
				(font
					(size 1.27 1.27)
				)
			)
		)
		(property "Value" ""
			(at 0 0 0)
			(layer "F.Fab")
			(effects
				(font
					(size 1.27 1.27)
				)
			)
		)
		(duplicate_pad_numbers_are_jumpers no)
		(fp_line
			(start 2.750058 0.999998)
			(end -2.750058 0.999998)
			(stroke
				(width 0.1524)
				(type default)
			)
			(layer "F.SilkS")
		)
		(fp_circle
			(center 0 0.999998)
			(end 2.750058 0.999998)
			(stroke
				(width 0.1524)
				(type default)
			)
			(fill no)
			(layer "F.SilkS")
		)
		(fp_poly
			(pts
				(arc
					(start 2.750058 0.999998)
					(mid 0 3.750056)
					(end -2.750058 0.999998)
				)
			)
			(stroke
				(width 0)
				(type default)
			)
			(fill yes)
			(layer "F.SilkS")
		)
		(fp_circle
			(center 0 0.999998)
			(end 2.750058 0.999998)
			(stroke
				(width 0.1)
				(type default)
			)
			(fill no)
			(layer "F.Fab")
		)
		(pad "1" thru_hole rect
			(at 0 0)
			(size 1.5748 1.5748)
			(drill 1.0668)
			(layers "*.Cu" "*.Mask")
			(remove_unused_layers no)
			(net "P1V05_PCH_AUX")
			(clearance 0)
			(padstack
				(mode front_inner_back)
				(layer "Inner"
					(shape circle)
					(size 1.5748 1.5748)
					(clearance 0)
				)
				(layer "B.Cu"
					(shape rect)
					(size 1.5748 1.5748)
					(clearance 0)
				)
			)
		)
		(pad "2" thru_hole circle
			(at 0 1.999996)
			(size 1.5748 1.5748)
			(drill 1.0668)
			(layers "*.Cu" "*.Mask")
			(remove_unused_layers no)
			(net "GND")
			(clearance 0)
		)
	)
	(footprint ""
		(layer "F.Cu")
		(at 181.7624 -94.338648 90)
		(property "Reference" "R4590"
			(at 0 0 90)
			(layer "F.SilkS")
			(hide yes)
			(effects
				(font
					(size 1.27 1.27)
				)
			)
		)
		(property "Value" ""
			(at 0 0 90)
			(layer "F.Fab")
			(effects
				(font
					(size 1.27 1.27)
				)
			)
		)
		(duplicate_pad_numbers_are_jumpers no)
		(fp_line
			(start 0.7874 -0.4064)
			(end 0.7874 0.4064)
			(stroke
				(width 0.1524)
				(type default)
			)
			(layer "F.SilkS")
		)
		(fp_line
			(start -0.7874 -0.4064)
			(end 0.7874 -0.4064)
			(stroke
				(width 0.1524)
				(type default)
			)
			(layer "F.SilkS")
		)
		(fp_line
			(start 0.7874 0.4064)
			(end -0.7874 0.4064)
			(stroke
				(width 0.1524)
				(type default)
			)
			(layer "F.SilkS")
		)
		(fp_line
			(start -0.7874 0.4064)
			(end -0.7874 -0.4064)
			(stroke
				(width 0.1524)
				(type default)
			)
			(layer "F.SilkS")
		)
		(fp_line
			(start -0.12065 -0.305054)
			(end -0.12065 -0.2794)
			(stroke
				(width 0.1)
				(type default)
			)
			(layer "F.Fab")
		)
		(fp_line
			(start -0.67945 -0.305054)
			(end -0.12065 -0.305054)
			(stroke
				(width 0.1)
				(type default)
			)
			(layer "F.Fab")
		)
		(fp_line
			(start 0.67945 -0.3048)
			(end 0.67945 0.3048)
			(stroke
				(width 0.1)
				(type default)
			)
			(layer "F.Fab")
		)
		(fp_line
			(start 0.12065 -0.3048)
			(end 0.67945 -0.3048)
			(stroke
				(width 0.1)
				(type default)
			)
			(layer "F.Fab")
		)
		(fp_line
			(start 0.12065 -0.2794)
			(end 0.12065 -0.3048)
			(stroke
				(width 0.1)
				(type default)
			)
			(layer "F.Fab")
		)
		(fp_line
			(start -0.12065 -0.2794)
			(end 0.12065 -0.2794)
			(stroke
				(width 0.1)
				(type default)
			)
			(layer "F.Fab")
		)
		(fp_line
			(start 0.120396 0.2794)
			(end -0.12065 0.2794)
			(stroke
				(width 0.1)
				(type default)
			)
			(layer "F.Fab")
		)
		(fp_line
			(start -0.12065 0.2794)
			(end -0.12065 0.3048)
			(stroke
				(width 0.1)
				(type default)
			)
			(layer "F.Fab")
		)
		(fp_line
			(start 0.67945 0.3048)
			(end 0.120396 0.3048)
			(stroke
				(width 0.1)
				(type default)
			)
			(layer "F.Fab")
		)
		(fp_line
			(start 0.120396 0.3048)
			(end 0.120396 0.2794)
			(stroke
				(width 0.1)
				(type default)
			)
			(layer "F.Fab")
		)
		(fp_line
			(start -0.12065 0.3048)
			(end -0.67945 0.3048)
			(stroke
				(width 0.1)
				(type default)
			)
			(layer "F.Fab")
		)
		(fp_line
			(start -0.67945 0.3048)
			(end -0.67945 -0.305054)
			(stroke
				(width 0.1)
				(type default)
			)
			(layer "F.Fab")
		)
		(pad "1" smd rect
			(at -0.40005 0 270)
			(size 0.4572 0.508)
			(layers "F.Cu" "F.Mask" "F.Paste")
			(net "FAB_BMC_REV_ID1")
		)
		(pad "2" smd rect
			(at 0.40005 0 270)
			(size 0.4572 0.508)
			(layers "F.Cu" "F.Mask" "F.Paste")
			(net "GND")
		)
	)
	(footprint ""
		(layer "F.Cu")
		(at 327.129902 -22.661626 -90)
		(property "Reference" "R4096"
			(at 0 0 270)
			(layer "F.SilkS")
			(hide yes)
			(effects
				(font
					(size 1.27 1.27)
				)
			)
		)
		(property "Value" ""
			(at 0 0 270)
			(layer "F.Fab")
			(effects
				(font
					(size 1.27 1.27)
				)
			)
		)
		(duplicate_pad_numbers_are_jumpers no)
		(fp_line
			(start -0.7874 0.4064)
			(end -0.7874 -0.4064)
			(stroke
				(width 0.1524)
				(type default)
			)
			(layer "F.SilkS")
		)
		(fp_line
			(start 0.7874 0.4064)
			(end -0.7874 0.4064)
			(stroke
				(width 0.1524)
				(type default)
			)
			(layer "F.SilkS")
		)
		(fp_line
			(start -0.7874 -0.4064)
			(end 0.7874 -0.4064)
			(stroke
				(width 0.1524)
				(type default)
			)
			(layer "F.SilkS")
		)
		(fp_line
			(start 0.7874 -0.4064)
			(end 0.7874 0.4064)
			(stroke
				(width 0.1524)
				(type default)
			)
			(layer "F.SilkS")
		)
		(fp_line
			(start -0.67945 0.3048)
			(end -0.67945 -0.305054)
			(stroke
				(width 0.1)
				(type default)
			)
			(layer "F.Fab")
		)
		(fp_line
			(start -0.12065 0.3048)
			(end -0.67945 0.3048)
			(stroke
				(width 0.1)
				(type default)
			)
			(layer "F.Fab")
		)
		(fp_line
			(start 0.120396 0.3048)
			(end 0.120396 0.2794)
			(stroke
				(width 0.1)
				(type default)
			)
			(layer "F.Fab")
		)
		(fp_line
			(start 0.67945 0.3048)
			(end 0.120396 0.3048)
			(stroke
				(width 0.1)
				(type default)
			)
			(layer "F.Fab")
		)
		(fp_line
			(start -0.12065 0.2794)
			(end -0.12065 0.3048)
			(stroke
				(width 0.1)
				(type default)
			)
			(layer "F.Fab")
		)
		(fp_line
			(start 0.120396 0.2794)
			(end -0.12065 0.2794)
			(stroke
				(width 0.1)
				(type default)
			)
			(layer "F.Fab")
		)
		(fp_line
			(start -0.12065 -0.2794)
			(end 0.12065 -0.2794)
			(stroke
				(width 0.1)
				(type default)
			)
			(layer "F.Fab")
		)
		(fp_line
			(start 0.12065 -0.2794)
			(end 0.12065 -0.3048)
			(stroke
				(width 0.1)
				(type default)
			)
			(layer "F.Fab")
		)
		(fp_line
			(start 0.12065 -0.3048)
			(end 0.67945 -0.3048)
			(stroke
				(width 0.1)
				(type default)
			)
			(layer "F.Fab")
		)
		(fp_line
			(start 0.67945 -0.3048)
			(end 0.67945 0.3048)
			(stroke
				(width 0.1)
				(type default)
			)
			(layer "F.Fab")
		)
		(fp_line
			(start -0.67945 -0.305054)
			(end -0.12065 -0.305054)
			(stroke
				(width 0.1)
				(type default)
			)
			(layer "F.Fab")
		)
		(fp_line
			(start -0.12065 -0.305054)
			(end -0.12065 -0.2794)
			(stroke
				(width 0.1)
				(type default)
			)
			(layer "F.Fab")
		)
		(pad "1" smd circle
			(at -0.40005 0 270)
			(size 0 0)
			(layers "F.Cu" "F.Mask" "F.Paste")
			(net "PD_PCH_GPPC_A_18")
		)
		(pad "2" smd circle
			(at 0.40005 0 270)
			(size 0 0)
			(layers "F.Cu" "F.Mask" "F.Paste")
			(net "GND")
		)
	)
	(footprint ""
		(layer "F.Cu")
		(at 113.882424 -37.01034 180)
		(property "Reference" "R4514"
			(at 0 0 180)
			(layer "F.SilkS")
			(hide yes)
			(effects
				(font
					(size 1.27 1.27)
				)
			)
		)
		(property "Value" ""
			(at 0 0 180)
			(layer "F.Fab")
			(effects
				(font
					(size 1.27 1.27)
				)
			)
		)
		(duplicate_pad_numbers_are_jumpers no)
		(fp_line
			(start 0.7874 0.4064)
			(end -0.7874 0.4064)
			(stroke
				(width 0.1524)
				(type default)
			)
			(layer "F.SilkS")
		)
		(fp_line
			(start 0.7874 -0.4064)
			(end 0.7874 0.4064)
			(stroke
				(width 0.1524)
				(type default)
			)
			(layer "F.SilkS")
		)
		(fp_line
			(start -0.7874 0.4064)
			(end -0.7874 -0.4064)
			(stroke
				(width 0.1524)
				(type default)
			)
			(layer "F.SilkS")
		)
		(fp_line
			(start -0.7874 -0.4064)
			(end 0.7874 -0.4064)
			(stroke
				(width 0.1524)
				(type default)
			)
			(layer "F.SilkS")
		)
		(fp_line
			(start 0.67945 0.3048)
			(end 0.120396 0.3048)
			(stroke
				(width 0.1)
				(type default)
			)
			(layer "F.Fab")
		)
		(fp_line
			(start 0.67945 -0.3048)
			(end 0.67945 0.3048)
			(stroke
				(width 0.1)
				(type default)
			)
			(layer "F.Fab")
		)
		(fp_line
			(start 0.12065 -0.2794)
			(end 0.12065 -0.3048)
			(stroke
				(width 0.1)
				(type default)
			)
			(layer "F.Fab")
		)
		(fp_line
			(start 0.12065 -0.3048)
			(end 0.67945 -0.3048)
			(stroke
				(width 0.1)
				(type default)
			)
			(layer "F.Fab")
		)
		(fp_line
			(start 0.120396 0.3048)
			(end 0.120396 0.2794)
			(stroke
				(width 0.1)
				(type default)
			)
			(layer "F.Fab")
		)
		(fp_line
			(start 0.120396 0.2794)
			(end -0.12065 0.2794)
			(stroke
				(width 0.1)
				(type default)
			)
			(layer "F.Fab")
		)
		(fp_line
			(start -0.12065 0.3048)
			(end -0.67945 0.3048)
			(stroke
				(width 0.1)
				(type default)
			)
			(layer "F.Fab")
		)
		(fp_line
			(start -0.12065 0.2794)
			(end -0.12065 0.3048)
			(stroke
				(width 0.1)
				(type default)
			)
			(layer "F.Fab")
		)
		(fp_line
			(start -0.12065 -0.2794)
			(end 0.12065 -0.2794)
			(stroke
				(width 0.1)
				(type default)
			)
			(layer "F.Fab")
		)
		(fp_line
			(start -0.12065 -0.305054)
			(end -0.12065 -0.2794)
			(stroke
				(width 0.1)
				(type default)
			)
			(layer "F.Fab")
		)
		(fp_line
			(start -0.67945 0.3048)
			(end -0.67945 -0.305054)
			(stroke
				(width 0.1)
				(type default)
			)
			(layer "F.Fab")
		)
		(fp_line
			(start -0.67945 -0.305054)
			(end -0.12065 -0.305054)
			(stroke
				(width 0.1)
				(type default)
			)
			(layer "F.Fab")
		)
		(pad "1" smd circle
			(at -0.40005 0 180)
			(size 0 0)
			(layers "F.Cu" "F.Mask" "F.Paste")
			(net "CLK_GEN2_GPU_FPGA_OE_R2_N")
		)
		(pad "2" smd circle
			(at 0.40005 0 180)
			(size 0 0)
			(layers "F.Cu" "F.Mask" "F.Paste")
			(net "GND")
		)
	)
	(footprint ""
		(layer "F.Cu")
		(at 423.096436 -366.66932 -90)
		(property "Reference" "PC1351"
			(at 0 0 270)
			(layer "F.SilkS")
			(hide yes)
			(effects
				(font
					(size 1.27 1.27)
				)
			)
		)
		(property "Value" ""
			(at 0 0 270)
			(layer "F.Fab")
			(effects
				(font
					(size 1.27 1.27)
				)
			)
		)
		(duplicate_pad_numbers_are_jumpers no)
		(fp_line
			(start -0.7874 0.4064)
			(end -0.7874 -0.4064)
			(stroke
				(width 0.1524)
				(type default)
			)
			(layer "F.SilkS")
		)
		(fp_line
			(start 0.7874 0.4064)
			(end -0.7874 0.4064)
			(stroke
				(width 0.1524)
				(type default)
			)
			(layer "F.SilkS")
		)
		(fp_line
			(start -0.7874 -0.4064)
			(end 0.7874 -0.4064)
			(stroke
				(width 0.1524)
				(type default)
			)
			(layer "F.SilkS")
		)
		(fp_line
			(start 0.7874 -0.4064)
			(end 0.7874 0.4064)
			(stroke
				(width 0.1524)
				(type default)
			)
			(layer "F.SilkS")
		)
		(fp_line
			(start -0.67945 0.3048)
			(end -0.67945 -0.305054)
			(stroke
				(width 0.1)
				(type default)
			)
			(layer "F.Fab")
		)
		(fp_line
			(start -0.12065 0.3048)
			(end -0.67945 0.3048)
			(stroke
				(width 0.1)
				(type default)
			)
			(layer "F.Fab")
		)
		(fp_line
			(start 0.120396 0.3048)
			(end 0.120396 0.2794)
			(stroke
				(width 0.1)
				(type default)
			)
			(layer "F.Fab")
		)
		(fp_line
			(start 0.67945 0.3048)
			(end 0.120396 0.3048)
			(stroke
				(width 0.1)
				(type default)
			)
			(layer "F.Fab")
		)
		(fp_line
			(start -0.12065 0.2794)
			(end -0.12065 0.3048)
			(stroke
				(width 0.1)
				(type default)
			)
			(layer "F.Fab")
		)
		(fp_line
			(start 0.120396 0.2794)
			(end -0.12065 0.2794)
			(stroke
				(width 0.1)
				(type default)
			)
			(layer "F.Fab")
		)
		(fp_line
			(start -0.12065 -0.2794)
			(end 0.12065 -0.2794)
			(stroke
				(width 0.1)
				(type default)
			)
			(layer "F.Fab")
		)
		(fp_line
			(start 0.12065 -0.2794)
			(end 0.12065 -0.3048)
			(stroke
				(width 0.1)
				(type default)
			)
			(layer "F.Fab")
		)
		(fp_line
			(start 0.12065 -0.3048)
			(end 0.67945 -0.3048)
			(stroke
				(width 0.1)
				(type default)
			)
			(layer "F.Fab")
		)
		(fp_line
			(start 0.67945 -0.3048)
			(end 0.67945 0.3048)
			(stroke
				(width 0.1)
				(type default)
			)
			(layer "F.Fab")
		)
		(fp_line
			(start -0.67945 -0.305054)
			(end -0.12065 -0.305054)
			(stroke
				(width 0.1)
				(type default)
			)
			(layer "F.Fab")
		)
		(fp_line
			(start -0.12065 -0.305054)
			(end -0.12065 -0.2794)
			(stroke
				(width 0.1)
				(type default)
			)
			(layer "F.Fab")
		)
		(pad "1" smd circle
			(at -0.40005 0 270)
			(size 0 0)
			(layers "F.Cu" "F.Mask" "F.Paste")
			(net "GND")
		)
		(pad "2" smd circle
			(at 0.40005 0 270)
			(size 0 0)
			(layers "F.Cu" "F.Mask" "F.Paste")
			(net "PVCCIN_CPU0_VREF")
		)
	)
	(footprint ""
		(layer "F.Cu")
		(at 232.911396 -245.411498 90)
		(property "Reference" "R4076"
			(at 0 0 90)
			(layer "F.SilkS")
			(hide yes)
			(effects
				(font
					(size 1.27 1.27)
				)
			)
		)
		(property "Value" ""
			(at 0 0 90)
			(layer "F.Fab")
			(effects
				(font
					(size 1.27 1.27)
				)
			)
		)
		(duplicate_pad_numbers_are_jumpers no)
		(fp_line
			(start 0.7874 -0.4064)
			(end 0.7874 0.4064)
			(stroke
				(width 0.1524)
				(type default)
			)
			(layer "F.SilkS")
		)
		(fp_line
			(start -0.7874 -0.4064)
			(end 0.7874 -0.4064)
			(stroke
				(width 0.1524)
				(type default)
			)
			(layer "F.SilkS")
		)
		(fp_line
			(start 0.7874 0.4064)
			(end -0.7874 0.4064)
			(stroke
				(width 0.1524)
				(type default)
			)
			(layer "F.SilkS")
		)
		(fp_line
			(start -0.7874 0.4064)
			(end -0.7874 -0.4064)
			(stroke
				(width 0.1524)
				(type default)
			)
			(layer "F.SilkS")
		)
		(fp_line
			(start -0.12065 -0.305054)
			(end -0.12065 -0.2794)
			(stroke
				(width 0.1)
				(type default)
			)
			(layer "F.Fab")
		)
		(fp_line
			(start -0.67945 -0.305054)
			(end -0.12065 -0.305054)
			(stroke
				(width 0.1)
				(type default)
			)
			(layer "F.Fab")
		)
		(fp_line
			(start 0.67945 -0.3048)
			(end 0.67945 0.3048)
			(stroke
				(width 0.1)
				(type default)
			)
			(layer "F.Fab")
		)
		(fp_line
			(start 0.12065 -0.3048)
			(end 0.67945 -0.3048)
			(stroke
				(width 0.1)
				(type default)
			)
			(layer "F.Fab")
		)
		(fp_line
			(start 0.12065 -0.2794)
			(end 0.12065 -0.3048)
			(stroke
				(width 0.1)
				(type default)
			)
			(layer "F.Fab")
		)
		(fp_line
			(start -0.12065 -0.2794)
			(end 0.12065 -0.2794)
			(stroke
				(width 0.1)
				(type default)
			)
			(layer "F.Fab")
		)
		(fp_line
			(start 0.120396 0.2794)
			(end -0.12065 0.2794)
			(stroke
				(width 0.1)
				(type default)
			)
			(layer "F.Fab")
		)
		(fp_line
			(start -0.12065 0.2794)
			(end -0.12065 0.3048)
			(stroke
				(width 0.1)
				(type default)
			)
			(layer "F.Fab")
		)
		(fp_line
			(start 0.67945 0.3048)
			(end 0.120396 0.3048)
			(stroke
				(width 0.1)
				(type default)
			)
			(layer "F.Fab")
		)
		(fp_line
			(start 0.120396 0.3048)
			(end 0.120396 0.2794)
			(stroke
				(width 0.1)
				(type default)
			)
			(layer "F.Fab")
		)
		(fp_line
			(start -0.12065 0.3048)
			(end -0.67945 0.3048)
			(stroke
				(width 0.1)
				(type default)
			)
			(layer "F.Fab")
		)
		(fp_line
			(start -0.67945 0.3048)
			(end -0.67945 -0.305054)
			(stroke
				(width 0.1)
				(type default)
			)
			(layer "F.Fab")
		)
		(pad "1" smd circle
			(at -0.40005 0 90)
			(size 0 0)
			(layers "F.Cu" "F.Mask" "F.Paste")
			(net "CLK_GEN2_GPU_FPGA_OE_OR_N")
		)
		(pad "2" smd circle
			(at 0.40005 0 90)
			(size 0 0)
			(layers "F.Cu" "F.Mask" "F.Paste")
			(net "CLK_GEN2_GPU_OE_N")
		)
	)
)
